FILE_TYPE = MULTI_PHYS_TABLE;

PART 'SCONN288_DDR506112002KQ'

{========================================================================================}
:VALUE                     | PART_TYPE | MATERIAL | PART_NUMBER    = STANDARD        | LIFECYCLE          | PART_NUMBER   | JEDEC_TYPE       | DESCRIPTION                                | MANUFTR | MANUF_PN         | RD_CMPLS_LVL | CMPLS_LVL | CLASS | DIP_SMD | FROM_PJ    | DATA                     | FP_ECN               | EE_CHECK_LIST | CREATOR | CREATEDAY  | PSL | STATUS | ESD_CDM | ESD_HBM | ESD_MM | MSD | PIN_LENGTH_LONG_PIN | PIN_LENGTH_SHORT_PIN ;
{========================================================================================}
 'SCONN288_DDR506112002KQ' | 'SMLF'    | 'IO'     | 'DFHST8FS479'(!) = ''               | ''               | 'DFHST8FS479' |'DDR288S_1-1VXC'| 'CONN SMD HS DDR5 288P 2R FS(P0.85,H21.3)' | 'APL'   | 'DDR506112002KQ' | 'EP(V1)'     | ''        | 'IO'  | ''      | 'T6G-JOHN' | 'APL_DDR506112002KQ.pdf' | 'DDR506112002KQ.msg' | ''            | ''      | '20211001' | ''  | ''     | ''      | ''      | ''     | ''  | '105 MILS'          | '105 MILS'          
 'SCONN288_DDR506112002KQ' | 'SMLF'    | 'EMPTY'  | 'DFHST8FS479'(!) = ''               | ''               | 'DFHST8FS479' |'DDR288S_1-1VXC'| 'CONN SMD HS DDR5 288P 2R FS(P0.85,H21.3)' | 'APL'   | 'DDR506112002KQ' | 'EP(V1)'     | ''        | 'IO'  | ''      | 'T6G-JOHN' | 'APL_DDR506112002KQ.pdf' | 'DDR506112002KQ.msg' | ''            | ''      | '20211001' | ''  | ''     | ''      | ''      | ''     | ''  | '105 MILS'          | '105 MILS'          

END_PART

END.

